FILE_TYPE = MULTI_PHYS_TABLE;

PART '74LVC1G08W57'

{========================================================================================}
:VALUE           | PART_TYPE | MATERIAL | PART_NUMBER    = STANDARD | LIFECYCLE      | PART_NUMBER   | JEDEC_TYPE           | DESCRIPTION                         | MANUFTR | MANUF_PN        | RD_CMPLS_LVL | CMPLS_LVL | FROM_PJ    | CLASS | DIP_SMD | DATA                    | EE_CHECK_LIST | FP_ECN | PSL | CREATOR | STATUS | MSD | ESD_CDM | ESD_HBM | ESD_MM | PIN_LENGTH_SHORT_PIN | PIN_LENGTH_LONG_PIN | CREATEDAY  ;
{========================================================================================}
 '74LVC1G08W5-7' | 'SMLF'    | 'IC'     | 'AL1G0008020'(!) = ''       | ''               | 'AL1G0008020' |'SOT25-5_0-95_3X1-6'| 'IC OTHER(5P) 74LVC1G08W5-7(SOT25)' | 'DDS'   | '74LVC1G08W5-7' | 'EP(V1)'     | 'EP(V1)'  | 'S6S-KYLE' | 'IC'  | ''      | 'DDS_74LVC1G08W5-7.pdf' | ''            | ''     | ''  | ''      | ''     | ''  | ''      | ''      | ''     | '0 MILS'             | '0 MILS'            | '20210604'
 '74LVC1G08W5-7' | 'SMLF'    | 'EMPTY'  | 'AL1G0008020'(!) = ''       | ''               | 'AL1G0008020' |'SOT25-5_0-95_3X1-6'| 'IC OTHER(5P) 74LVC1G08W5-7(SOT25)' | 'DDS'   | '74LVC1G08W5-7' | 'EP(V1)'     | 'EP(V1)'  | 'S6S-KYLE' | 'IC'  | ''      | 'DDS_74LVC1G08W5-7.pdf' | ''            | ''     | ''  | ''      | ''     | ''  | ''      | ''      | ''     | '0 MILS'             | '0 MILS'            | '20210604'

END_PART

END.

